(kicad_pcb
	(version 20260206)
	(generator "pcbnew")
	(generator_version "10.0")
	(general
		(thickness 1.6)
		(legacy_teardrops no)
	)
	(paper "A4")
	(title_block
		(title "9052_F0T_PDB_Converter_Brick_F_V03_1208_1600_OCP.brd")
		(comment 1 "Grand Teton / footprints 161-167 of 578")
	)
	(layers
		(0 "F.Cu" signal "TOP")
		(4 "In1.Cu" signal "GND")
		(6 "In2.Cu" signal "IN1")
		(8 "In3.Cu" signal "GND1")
		(10 "In4.Cu" signal "VCC")
		(12 "In5.Cu" signal "VCC1")
		(14 "In6.Cu" signal "GND2")
		(16 "In7.Cu" signal "IN2")
		(18 "In8.Cu" signal "GND3")
		(2 "B.Cu" signal "BOTTOM")
		(9 "F.Adhes" user "F.Adhesive")
		(11 "B.Adhes" user "B.Adhesive")
		(13 "F.Paste" user "Package Geometry/Pastemask Top")
		(15 "B.Paste" user "Package Geometry/Pastemask Bottom")
		(5 "F.SilkS" user "Ref Des/Silkscreen Top")
		(7 "B.SilkS" user "Ref Des/Silkscreen Bottom")
		(1 "F.Mask" user "Board Geometry/Soldermask Top")
		(3 "B.Mask" user "Board Geometry/Soldermask Bottom")
		(17 "Dwgs.User" user "User.Drawings")
		(19 "Cmts.User" user "User.Comments")
		(21 "Eco1.User" user "User.Eco1")
		(23 "Eco2.User" user "User.Eco2")
		(25 "Edge.Cuts" user "Board Geometry/Outline")
		(27 "Margin" user)
		(31 "F.CrtYd" user "Package Geometry/Place Bound Top")
		(29 "B.CrtYd" user "Package Geometry/Place Bound Bottom")
		(35 "F.Fab" user "Ref Des/Assembly Top")
		(33 "B.Fab" user "Ref Des/Assembly Bottom")
	)
	(footprint ""
		(layer "F.Cu")
		(at 184.470294 -121.209816)
		(property "Reference" "PU6"
			(at -26.563066 -5.12953 0)
			(unlocked yes)
			(layer "F.SilkS")
			(effects
				(font
					(size 0.7874 0.5842)
					(thickness 0.1524)
				)
				(justify left)
			)
		)
		(property "Value" ""
			(at 0 0 0)
			(layer "F.Fab")
			(effects
				(font
					(size 1.27 1.27)
				)
			)
		)
		(duplicate_pad_numbers_are_jumpers no)
		(fp_line
			(start -26.519886 -4.299966)
			(end -26.519886 55.099966)
			(stroke
				(width 0.1524)
				(type default)
			)
			(layer "F.SilkS")
		)
		(fp_line
			(start -26.519886 55.099966)
			(end 11.279886 55.099966)
			(stroke
				(width 0.1524)
				(type default)
			)
			(layer "F.SilkS")
		)
		(fp_line
			(start -26.020014 -3.800094)
			(end -26.020014 54.59984)
			(stroke
				(width 0.1524)
				(type default)
			)
			(layer "F.SilkS")
		)
		(fp_line
			(start -26.020014 54.59984)
			(end 10.780014 54.59984)
			(stroke
				(width 0.1524)
				(type default)
			)
			(layer "F.SilkS")
		)
		(fp_line
			(start 10.780014 -3.800094)
			(end -26.020014 -3.800094)
			(stroke
				(width 0.1524)
				(type default)
			)
			(layer "F.SilkS")
		)
		(fp_line
			(start 10.780014 54.59984)
			(end 10.780014 -3.800094)
			(stroke
				(width 0.1524)
				(type default)
			)
			(layer "F.SilkS")
		)
		(fp_line
			(start 11.279886 -4.299966)
			(end -26.519886 -4.299966)
			(stroke
				(width 0.1524)
				(type default)
			)
			(layer "F.SilkS")
		)
		(fp_line
			(start 11.279886 55.099966)
			(end 11.279886 -4.299966)
			(stroke
				(width 0.1524)
				(type default)
			)
			(layer "F.SilkS")
		)
		(fp_poly
			(pts
				(xy 1.27 -7.44728) (xy -1.27 -7.44728) (xy 0 -4.90728)
			)
			(stroke
				(width 0)
				(type default)
			)
			(fill yes)
			(layer "F.SilkS")
		)
		(fp_line
			(start -26.020014 -3.800094)
			(end -26.020014 54.59984)
			(stroke
				(width 0.1)
				(type default)
			)
			(layer "F.Fab")
		)
		(fp_line
			(start -26.020014 54.59984)
			(end 10.780014 54.59984)
			(stroke
				(width 0.1)
				(type default)
			)
			(layer "F.Fab")
		)
		(fp_line
			(start 10.780014 -3.800094)
			(end -26.020014 -3.800094)
			(stroke
				(width 0.1)
				(type default)
			)
			(layer "F.Fab")
		)
		(fp_line
			(start 10.780014 54.59984)
			(end 10.780014 -3.800094)
			(stroke
				(width 0.1)
				(type default)
			)
			(layer "F.Fab")
		)
		(fp_poly
			(pts
				(xy 1.27 -7.44728) (xy -1.27 -7.44728) (xy 0 -4.90728)
			)
			(stroke
				(width 0)
				(type default)
			)
			(fill yes)
			(layer "F.Fab")
		)
		(pad "1" thru_hole rect
			(at 0 0 270)
			(size 2.3622 2.3622)
			(drill 1.6002)
			(layers "*.Cu" "*.Mask")
			(remove_unused_layers no)
			(net "P52V_HS_FILTER")
			(clearance -0.127)
			(padstack
				(mode front_inner_back)
				(layer "Inner"
					(shape circle)
					(size 2.3622 2.3622)
					(clearance -0.127)
				)
				(layer "B.Cu"
					(shape rect)
					(size 2.3622 2.3622)
					(clearance -0.127)
				)
			)
		)
		(pad "2" thru_hole circle
			(at -7.62 0 270)
			(size 2.3622 2.3622)
			(drill 1.6002)
			(layers "*.Cu" "*.Mask")
			(remove_unused_layers no)
			(net "BRICK_P12V2_ON_OFF_R")
			(clearance -0.127)
		)
		(pad "3" thru_hole circle
			(at -15.24 0 270)
			(size 2.3622 2.3622)
			(drill 1.6002)
			(layers "*.Cu" "*.Mask")
			(remove_unused_layers no)
			(net "GND")
			(clearance -0.127)
		)
		(pad "4" thru_hole circle
			(at -19.05 50.8 270)
			(size 3.1242 3.1242)
			(drill 2.1082)
			(layers "*.Cu" "*.Mask")
			(remove_unused_layers no)
			(net "GND")
			(clearance -0.254)
		)
		(pad "5" thru_hole circle
			(at -15.24 50.8 270)
			(size 3.1242 3.1242)
			(drill 2.1082)
			(layers "*.Cu" "*.Mask")
			(remove_unused_layers no)
			(net "GND")
			(clearance -0.254)
		)
		(pad "6" thru_hole circle
			(at 0 50.8 270)
			(size 3.1242 3.1242)
			(drill 2.1082)
			(layers "*.Cu" "*.Mask")
			(remove_unused_layers no)
			(net "P12V_BRICK")
			(clearance -0.254)
		)
		(pad "7" thru_hole circle
			(at 3.81 50.8 270)
			(size 3.1242 3.1242)
			(drill 2.1082)
			(layers "*.Cu" "*.Mask")
			(remove_unused_layers no)
			(net "P12V_BRICK")
			(clearance -0.254)
		)
		(pad "8" thru_hole circle
			(at -13.619988 53.34 270)
			(size 1.3208 1.3208)
			(drill 0.9144)
			(layers "*.Cu" "*.Mask")
			(remove_unused_layers no)
			(net "P12V_BRICK_PWRGD")
			(clearance 0.0508)
			(thermal_gap 0.0508)
		)
		(pad "9" thru_hole circle
			(at -11.619992 53.34 270)
			(size 1.3208 1.3208)
			(drill 0.9144)
			(layers "*.Cu" "*.Mask")
			(remove_unused_layers no)
			(net "P12V_MB2_SENSE-")
			(clearance 0.0508)
			(thermal_gap 0.0508)
		)
		(pad "10" thru_hole circle
			(at -9.619996 53.34 270)
			(size 1.3208 1.3208)
			(drill 0.9144)
			(layers "*.Cu" "*.Mask")
			(remove_unused_layers no)
			(net "SMB_BRICK2_SDA")
			(clearance 0.0508)
			(thermal_gap 0.0508)
		)
		(pad "11" thru_hole circle
			(at -7.62 53.34 270)
			(size 1.3208 1.3208)
			(drill 0.9144)
			(layers "*.Cu" "*.Mask")
			(remove_unused_layers no)
			(net "SMB_BRICK2_ALERT")
			(clearance 0.0508)
			(thermal_gap 0.0508)
		)
		(pad "12" thru_hole circle
			(at -5.620004 53.34 270)
			(size 1.3208 1.3208)
			(drill 0.9144)
			(layers "*.Cu" "*.Mask")
			(remove_unused_layers no)
			(net "SMB_BRICK2_SCL")
			(clearance 0.0508)
			(thermal_gap 0.0508)
		)
		(pad "13" thru_hole circle
			(at -3.620008 53.34 270)
			(size 1.3208 1.3208)
			(drill 0.9144)
			(layers "*.Cu" "*.Mask")
			(remove_unused_layers no)
			(net "BRICK2_PMBADD")
			(clearance 0.0508)
			(thermal_gap 0.0508)
		)
		(pad "14" thru_hole circle
			(at -1.620012 53.34 270)
			(size 1.3208 1.3208)
			(drill 0.9144)
			(layers "*.Cu" "*.Mask")
			(remove_unused_layers no)
			(net "P12V_MB2_SENSE+")
			(clearance 0.0508)
			(thermal_gap 0.0508)
		)
	)
	(footprint ""
		(layer "F.Cu")
		(at 280.39568 -78.217268)
		(property "Reference" "PQ5"
			(at -7.723886 -5.895848 0)
			(unlocked yes)
			(layer "F.SilkS")
			(effects
				(font
					(size 0.7874 0.5842)
					(thickness 0.1524)
				)
				(justify left)
			)
		)
		(property "Value" ""
			(at 0 0 0)
			(layer "F.Fab")
			(effects
				(font
					(size 1.27 1.27)
				)
			)
		)
		(duplicate_pad_numbers_are_jumpers no)
		(fp_line
			(start -7.649972 -4.99999)
			(end -7.649972 -3.3274)
			(stroke
				(width 0.1524)
				(type default)
			)
			(layer "F.SilkS")
		)
		(fp_line
			(start -7.649972 -1.7526)
			(end -7.649972 1.7526)
			(stroke
				(width 0.1524)
				(type default)
			)
			(layer "F.SilkS")
		)
		(fp_line
			(start -7.649972 3.3274)
			(end -7.649972 4.99999)
			(stroke
				(width 0.1524)
				(type default)
			)
			(layer "F.SilkS")
		)
		(fp_line
			(start -7.649972 4.99999)
			(end 5.115814 4.99999)
			(stroke
				(width 0.1524)
				(type default)
			)
			(layer "F.SilkS")
		)
		(fp_line
			(start 5.115814 -4.99999)
			(end -7.649972 -4.99999)
			(stroke
				(width 0.1524)
				(type default)
			)
			(layer "F.SilkS")
		)
		(fp_line
			(start 7.630414 4.99999)
			(end 7.649972 4.99999)
			(stroke
				(width 0.1524)
				(type default)
			)
			(layer "F.SilkS")
		)
		(fp_line
			(start 7.649972 -4.99999)
			(end 7.630414 -4.99999)
			(stroke
				(width 0.1524)
				(type default)
			)
			(layer "F.SilkS")
		)
		(fp_line
			(start 7.649972 4.99999)
			(end 7.649972 -4.99999)
			(stroke
				(width 0.1524)
				(type default)
			)
			(layer "F.SilkS")
		)
		(fp_line
			(start -7.649972 -4.99999)
			(end -7.649972 4.99999)
			(stroke
				(width 0.1)
				(type default)
			)
			(layer "F.Fab")
		)
		(fp_line
			(start -7.649972 4.99999)
			(end 7.649972 4.99999)
			(stroke
				(width 0.1)
				(type default)
			)
			(layer "F.Fab")
		)
		(fp_line
			(start 7.649972 -4.99999)
			(end -7.649972 -4.99999)
			(stroke
				(width 0.1)
				(type default)
			)
			(layer "F.Fab")
		)
		(fp_line
			(start 7.649972 4.99999)
			(end 7.649972 -4.99999)
			(stroke
				(width 0.1)
				(type default)
			)
			(layer "F.Fab")
		)
		(pad "D" smd circle
			(at 2.15011 0)
			(size 0 0)
			(layers "F.Cu" "F.Mask" "F.Paste")
			(net "P52V_HS1_DRAIN_2")
		)
		(pad "G" smd rect
			(at -7.050024 -2.54 270)
			(size 1.3208 3.0988)
			(layers "F.Cu" "F.Mask" "F.Paste")
			(net "P52V_HS1_GATE5")
		)
		(pad "S" smd rect
			(at -7.050024 2.54 270)
			(size 1.3208 3.0988)
			(layers "F.Cu" "F.Mask" "F.Paste")
			(net "P52V_HS")
		)
		(zone
			(layer "F.Cu")
			(hatch none 0.5)
			(connect_pads
				(clearance 0)
			)
			(min_thickness 0.25)
			(keepout
				(tracks not_allowed)
				(vias allowed)
				(pads allowed)
				(copperpour not_allowed)
				(footprints allowed)
			)
			(placement
				(enabled no)
				(sheetname "")
			)
			(fill
				(thermal_gap 0.5)
				(thermal_bridge_width 0.5)
				(island_removal_mode 0)
			)
			(polygon
				(pts
					(xy 285.57728 -83.195668) (xy 272.75028 -83.195668) (xy 272.75028 -81.468468) (xy 274.96008 -81.468468)
					(xy 274.96008 -80.046068) (xy 272.75028 -80.046068) (xy 272.75028 -76.388468) (xy 274.96008 -76.388468)
					(xy 274.96008 -74.966068) (xy 272.75028 -74.966068) (xy 272.75028 -73.238868) (xy 285.57728 -73.238868)
					(xy 285.57728 -74.407268) (xy 279.37968 -74.407268) (xy 279.37968 -82.027268) (xy 285.57728 -82.027268)
				)
			)
		)
	)
	(footprint ""
		(layer "F.Cu")
		(at 109.097826 -127.889)
		(property "Reference" "PC46"
			(at 0 0 0)
			(layer "F.SilkS")
			(hide yes)
			(effects
				(font
					(size 1.27 1.27)
				)
			)
		)
		(property "Value" ""
			(at 0 0 0)
			(layer "F.Fab")
			(effects
				(font
					(size 1.27 1.27)
				)
			)
		)
		(duplicate_pad_numbers_are_jumpers no)
		(fp_line
			(start -2.2098 -0.9398)
			(end 2.2098 -0.9398)
			(stroke
				(width 0.1524)
				(type default)
			)
			(layer "F.SilkS")
		)
		(fp_line
			(start -2.2098 0.9398)
			(end -2.2098 -0.9398)
			(stroke
				(width 0.1524)
				(type default)
			)
			(layer "F.SilkS")
		)
		(fp_line
			(start 2.2098 -0.9398)
			(end 2.2098 0.9398)
			(stroke
				(width 0.1524)
				(type default)
			)
			(layer "F.SilkS")
		)
		(fp_line
			(start 2.2098 0.9398)
			(end -2.2098 0.9398)
			(stroke
				(width 0.1524)
				(type default)
			)
			(layer "F.SilkS")
		)
		(fp_line
			(start -1.700022 -0.899922)
			(end 1.700022 -0.899922)
			(stroke
				(width 0.1)
				(type default)
			)
			(layer "F.Fab")
		)
		(fp_line
			(start -1.700022 0.899922)
			(end -1.700022 -0.899922)
			(stroke
				(width 0.1)
				(type default)
			)
			(layer "F.Fab")
		)
		(fp_line
			(start 1.700022 -0.899922)
			(end 1.700022 0.899922)
			(stroke
				(width 0.1)
				(type default)
			)
			(layer "F.Fab")
		)
		(fp_line
			(start 1.700022 0.899922)
			(end -1.700022 0.899922)
			(stroke
				(width 0.1)
				(type default)
			)
			(layer "F.Fab")
		)
		(pad "1" smd rect
			(at -1.4732 0 180)
			(size 1.1684 1.5748)
			(layers "F.Cu" "F.Mask" "F.Paste")
			(net "P52V_HS_FILTER")
		)
		(pad "2" smd rect
			(at 1.4732 0 180)
			(size 1.1684 1.5748)
			(layers "F.Cu" "F.Mask" "F.Paste")
			(net "GND")
		)
	)
	(footprint ""
		(layer "F.Cu")
		(at 298.91101 -141.069568)
		(property "Reference" ""
			(at 0 0 0)
			(layer "F.SilkS")
			(hide yes)
			(effects
				(font
					(size 1.27 1.27)
				)
			)
		)
		(property "Value" ""
			(at 0 0 0)
			(layer "F.Fab")
			(effects
				(font
					(size 1.27 1.27)
				)
			)
		)
		(duplicate_pad_numbers_are_jumpers no)
		(pad "1" smd circle
			(at 0 0)
			(size 0.9906 0.9906)
			(layers "F.Cu" "F.Mask" "F.Paste")
			(net "Net_154")
		)
		(zone
			(layer "F.Cu")
			(hatch none 0.5)
			(connect_pads
				(clearance 0)
			)
			(min_thickness 0.25)
			(keepout
				(tracks not_allowed)
				(vias allowed)
				(pads allowed)
				(copperpour not_allowed)
				(footprints allowed)
			)
			(placement
				(enabled no)
				(sheetname "")
			)
			(fill
				(thermal_gap 0.5)
				(thermal_bridge_width 0.5)
				(island_removal_mode 0)
			)
			(polygon
				(pts
					(arc
						(start 300.53661 -141.069568)
						(mid 297.28541 -141.069568)
						(end 300.53661 -141.069568)
					)
				)
			)
		)
	)
	(footprint ""
		(layer "F.Cu")
		(at 100.965 -50.038)
		(property "Reference" "PC67"
			(at 0 0 0)
			(layer "F.SilkS")
			(hide yes)
			(effects
				(font
					(size 1.27 1.27)
				)
			)
		)
		(property "Value" ""
			(at 0 0 0)
			(layer "F.Fab")
			(effects
				(font
					(size 1.27 1.27)
				)
			)
		)
		(duplicate_pad_numbers_are_jumpers no)
		(fp_line
			(start -1.524 -0.762)
			(end 1.524 -0.762)
			(stroke
				(width 0.1524)
				(type default)
			)
			(layer "F.SilkS")
		)
		(fp_line
			(start -1.524 0.762)
			(end -1.524 -0.762)
			(stroke
				(width 0.1524)
				(type default)
			)
			(layer "F.SilkS")
		)
		(fp_line
			(start 1.524 -0.762)
			(end 1.524 0.762)
			(stroke
				(width 0.1524)
				(type default)
			)
			(layer "F.SilkS")
		)
		(fp_line
			(start 1.524 0.762)
			(end -1.524 0.762)
			(stroke
				(width 0.1524)
				(type default)
			)
			(layer "F.SilkS")
		)
		(fp_line
			(start -1.1049 -0.724916)
			(end -1.1049 0.724916)
			(stroke
				(width 0.1)
				(type default)
			)
			(layer "F.Fab")
		)
		(fp_line
			(start -1.1049 0.724916)
			(end 1.1049 0.724916)
			(stroke
				(width 0.1)
				(type default)
			)
			(layer "F.Fab")
		)
		(fp_line
			(start 1.1049 -0.724916)
			(end -1.1049 -0.724916)
			(stroke
				(width 0.1)
				(type default)
			)
			(layer "F.Fab")
		)
		(fp_line
			(start 1.1049 0.724916)
			(end 1.1049 -0.724916)
			(stroke
				(width 0.1)
				(type default)
			)
			(layer "F.Fab")
		)
		(pad "1" smd rect
			(at -0.889 0 180)
			(size 1.016 1.27)
			(layers "F.Cu" "F.Mask" "F.Paste")
			(net "P12V_BRICK")
		)
		(pad "2" smd rect
			(at 0.889 0 180)
			(size 1.016 1.27)
			(layers "F.Cu" "F.Mask" "F.Paste")
			(net "GND")
		)
	)
	(footprint ""
		(layer "F.Cu")
		(at 100.076 -60.071)
		(property "Reference" "PR74"
			(at 0 0 0)
			(layer "F.SilkS")
			(hide yes)
			(effects
				(font
					(size 1.27 1.27)
				)
			)
		)
		(property "Value" ""
			(at 0 0 0)
			(layer "F.Fab")
			(effects
				(font
					(size 1.27 1.27)
				)
			)
		)
		(duplicate_pad_numbers_are_jumpers no)
		(fp_line
			(start -1.651 -0.8382)
			(end 1.651 -0.8382)
			(stroke
				(width 0.1524)
				(type default)
			)
			(layer "F.SilkS")
		)
		(fp_line
			(start -1.651 0.8382)
			(end -1.651 -0.8382)
			(stroke
				(width 0.1524)
				(type default)
			)
			(layer "F.SilkS")
		)
		(fp_line
			(start 1.651 -0.8382)
			(end 1.651 0.8382)
			(stroke
				(width 0.1524)
				(type default)
			)
			(layer "F.SilkS")
		)
		(fp_line
			(start 1.651 0.8382)
			(end -1.651 0.8382)
			(stroke
				(width 0.1524)
				(type default)
			)
			(layer "F.SilkS")
		)
		(fp_line
			(start -1.559814 -0.7366)
			(end -1.559814 0.7366)
			(stroke
				(width 0.1)
				(type default)
			)
			(layer "F.Fab")
		)
		(fp_line
			(start -1.559814 0.7366)
			(end -1.524 0.7366)
			(stroke
				(width 0.1)
				(type default)
			)
			(layer "F.Fab")
		)
		(fp_line
			(start -1.524 -0.7366)
			(end -1.559814 -0.7366)
			(stroke
				(width 0.1)
				(type default)
			)
			(layer "F.Fab")
		)
		(fp_line
			(start -1.524 0.7366)
			(end 1.524 0.7366)
			(stroke
				(width 0.1)
				(type default)
			)
			(layer "F.Fab")
		)
		(fp_line
			(start 1.524 -0.7366)
			(end -1.524 -0.7366)
			(stroke
				(width 0.1)
				(type default)
			)
			(layer "F.Fab")
		)
		(fp_line
			(start 1.524 0.7366)
			(end 1.560576 0.7366)
			(stroke
				(width 0.1)
				(type default)
			)
			(layer "F.Fab")
		)
		(fp_line
			(start 1.560576 -0.7366)
			(end 1.524 -0.7366)
			(stroke
				(width 0.1)
				(type default)
			)
			(layer "F.Fab")
		)
		(fp_line
			(start 1.560576 0.7366)
			(end 1.560576 -0.7366)
			(stroke
				(width 0.1)
				(type default)
			)
			(layer "F.Fab")
		)
		(pad "1" smd rect
			(at -0.94996 0 180)
			(size 1.1176 1.3716)
			(layers "F.Cu" "F.Mask" "F.Paste")
			(net "P12V_BRICK")
		)
		(pad "2" smd rect
			(at 0.94996 0 180)
			(size 1.1176 1.3716)
			(layers "F.Cu" "F.Mask" "F.Paste")
			(net "GND")
		)
	)
	(footprint ""
		(layer "F.Cu")
		(at 278.388318 -161.464498 90)
		(property "Reference" "J10"
			(at 1.222502 -5.580634 90)
			(unlocked yes)
			(layer "F.SilkS")
			(effects
				(font
					(size 0.7874 0.5842)
					(thickness 0.1524)
				)
				(justify left)
			)
		)
		(property "Value" ""
			(at 0 0 90)
			(layer "F.Fab")
			(effects
				(font
					(size 1.27 1.27)
				)
			)
		)
		(duplicate_pad_numbers_are_jumpers no)
		(fp_line
			(start 3.330702 -4.771136)
			(end 0 4.011168)
			(stroke
				(width 0.1524)
				(type default)
			)
			(layer "F.SilkS")
		)
		(fp_line
			(start -3.330702 -4.771136)
			(end 3.330702 -4.771136)
			(stroke
				(width 0.1524)
				(type default)
			)
			(layer "F.SilkS")
		)
		(fp_line
			(start 0 4.011168)
			(end -3.330702 -4.771136)
			(stroke
				(width 0.1524)
				(type default)
			)
			(layer "F.SilkS")
		)
		(fp_line
			(start 3.330702 -4.771136)
			(end 0 4.011168)
			(stroke
				(width 0.1)
				(type default)
			)
			(layer "F.Fab")
		)
		(fp_line
			(start -3.330702 -4.771136)
			(end 3.330702 -4.771136)
			(stroke
				(width 0.1)
				(type default)
			)
			(layer "F.Fab")
		)
		(fp_line
			(start 0 4.011168)
			(end -3.330702 -4.771136)
			(stroke
				(width 0.1)
				(type default)
			)
			(layer "F.Fab")
		)
		(pad "1" thru_hole circle
			(at 0 0 90)
			(size 2.159 2.159)
			(drill 1.7018)
			(layers "*.Cu" "*.Mask")
			(remove_unused_layers no)
			(net "GND3")
			(clearance 0.0254)
			(thermal_gap 0.0254)
		)
		(pad "2" thru_hole circle
			(at -1.27 -3.348736 90)
			(size 2.159 2.159)
			(drill 1.7018)
			(layers "*.Cu" "*.Mask")
			(remove_unused_layers no)
			(net "TDR_SE_50_OHM_TOP")
			(clearance 0.0254)
			(thermal_gap 0.0254)
		)
		(pad "3" thru_hole circle
			(at 1.27 -3.348736 90)
			(size 2.159 2.159)
			(drill 1.7018)
			(layers "*.Cu" "*.Mask")
			(remove_unused_layers no)
			(net "TDR_SE_50_OHM_TOP")
			(clearance 0.0254)
			(thermal_gap 0.0254)
		)
	)
)
